(kicad_pcb
	(version 20260206)
	(generator "pcbnew")
	(generator_version "10.0")
	(general
		(thickness 1.6)
		(legacy_teardrops no)
	)
	(paper "A4")
	(title_block
		(title "01162023_DA0F0TEBIF0_F0T_Expander_BD_F_brd_V02_OCP.brd")
		(comment 1 "Grand Teton / footprints 6832-6837 of 9728")
	)
	(layers
		(0 "F.Cu" signal "TOP")
		(4 "In1.Cu" signal "GND")
		(6 "In2.Cu" signal "VCC")
		(8 "In3.Cu" signal "VCC1")
		(10 "In4.Cu" signal "GND1")
		(12 "In5.Cu" signal "IN1")
		(14 "In6.Cu" signal "GND2")
		(16 "In7.Cu" signal "IN2")
		(18 "In8.Cu" signal "GND3")
		(20 "In9.Cu" signal "IN3")
		(22 "In10.Cu" signal "GND4")
		(24 "In11.Cu" signal "IN4")
		(26 "In12.Cu" signal "GND5")
		(28 "In13.Cu" signal "IN5")
		(30 "In14.Cu" signal "GND6")
		(32 "In15.Cu" signal "IN6")
		(34 "In16.Cu" signal "GND7")
		(2 "B.Cu" signal "BOTTOM")
		(9 "F.Adhes" user "F.Adhesive")
		(11 "B.Adhes" user "B.Adhesive")
		(13 "F.Paste" user "Package Geometry/Pastemask Top")
		(15 "B.Paste" user "Package Geometry/Pastemask Bottom")
		(5 "F.SilkS" user "Ref Des/Silkscreen Top")
		(7 "B.SilkS" user "Ref Des/Silkscreen Bottom")
		(1 "F.Mask" user "Board Geometry/Soldermask Top")
		(3 "B.Mask" user "Board Geometry/Soldermask Bottom")
		(17 "Dwgs.User" user "User.Drawings")
		(19 "Cmts.User" user "User.Comments")
		(21 "Eco1.User" user "User.Eco1")
		(23 "Eco2.User" user "User.Eco2")
		(25 "Edge.Cuts" user "Board Geometry/Outline")
		(27 "Margin" user)
		(31 "F.CrtYd" user "Package Geometry/Place Bound Top")
		(29 "B.CrtYd" user "Package Geometry/Place Bound Bottom")
		(35 "F.Fab" user "Ref Des/Assembly Top")
		(33 "B.Fab" user "Ref Des/Assembly Bottom")
	)
	(footprint ""
		(layer "F.Cu")
		(at 349.05061 -279.486868 -90)
		(property "Reference" "PC166"
			(at 0 0 270)
			(layer "F.SilkS")
			(hide yes)
			(effects
				(font
					(size 1.27 1.27)
				)
			)
		)
		(property "Value" ""
			(at 0 0 270)
			(layer "F.Fab")
			(effects
				(font
					(size 1.27 1.27)
				)
			)
		)
		(duplicate_pad_numbers_are_jumpers no)
		(fp_line
			(start -0.7874 0.4064)
			(end -0.7874 -0.4064)
			(stroke
				(width 0.1524)
				(type default)
			)
			(layer "F.SilkS")
		)
		(fp_line
			(start 0.7874 0.4064)
			(end -0.7874 0.4064)
			(stroke
				(width 0.1524)
				(type default)
			)
			(layer "F.SilkS")
		)
		(fp_line
			(start -0.7874 -0.4064)
			(end 0.7874 -0.4064)
			(stroke
				(width 0.1524)
				(type default)
			)
			(layer "F.SilkS")
		)
		(fp_line
			(start 0.7874 -0.4064)
			(end 0.7874 0.4064)
			(stroke
				(width 0.1524)
				(type default)
			)
			(layer "F.SilkS")
		)
		(fp_line
			(start -0.67945 0.3048)
			(end -0.67945 -0.305054)
			(stroke
				(width 0.1)
				(type default)
			)
			(layer "F.Fab")
		)
		(fp_line
			(start -0.12065 0.3048)
			(end -0.67945 0.3048)
			(stroke
				(width 0.1)
				(type default)
			)
			(layer "F.Fab")
		)
		(fp_line
			(start 0.120396 0.3048)
			(end 0.120396 0.2794)
			(stroke
				(width 0.1)
				(type default)
			)
			(layer "F.Fab")
		)
		(fp_line
			(start 0.67945 0.3048)
			(end 0.120396 0.3048)
			(stroke
				(width 0.1)
				(type default)
			)
			(layer "F.Fab")
		)
		(fp_line
			(start -0.12065 0.2794)
			(end -0.12065 0.3048)
			(stroke
				(width 0.1)
				(type default)
			)
			(layer "F.Fab")
		)
		(fp_line
			(start 0.120396 0.2794)
			(end -0.12065 0.2794)
			(stroke
				(width 0.1)
				(type default)
			)
			(layer "F.Fab")
		)
		(fp_line
			(start -0.12065 -0.2794)
			(end 0.12065 -0.2794)
			(stroke
				(width 0.1)
				(type default)
			)
			(layer "F.Fab")
		)
		(fp_line
			(start 0.12065 -0.2794)
			(end 0.12065 -0.3048)
			(stroke
				(width 0.1)
				(type default)
			)
			(layer "F.Fab")
		)
		(fp_line
			(start 0.12065 -0.3048)
			(end 0.67945 -0.3048)
			(stroke
				(width 0.1)
				(type default)
			)
			(layer "F.Fab")
		)
		(fp_line
			(start 0.67945 -0.3048)
			(end 0.67945 0.3048)
			(stroke
				(width 0.1)
				(type default)
			)
			(layer "F.Fab")
		)
		(fp_line
			(start -0.67945 -0.305054)
			(end -0.12065 -0.305054)
			(stroke
				(width 0.1)
				(type default)
			)
			(layer "F.Fab")
		)
		(fp_line
			(start -0.12065 -0.305054)
			(end -0.12065 -0.2794)
			(stroke
				(width 0.1)
				(type default)
			)
			(layer "F.Fab")
		)
		(pad "1" smd circle
			(at -0.40005 0 270)
			(size 0 0)
			(layers "F.Cu" "F.Mask" "F.Paste")
			(net "P0V8_PEX2_VREF")
		)
		(pad "2" smd circle
			(at 0.40005 0 270)
			(size 0 0)
			(layers "F.Cu" "F.Mask" "F.Paste")
			(net "GND")
		)
	)
	(footprint ""
		(layer "F.Cu")
		(at 387.882384 -252.356874 -90)
		(property "Reference" "R3965"
			(at 0 0 270)
			(layer "F.SilkS")
			(hide yes)
			(effects
				(font
					(size 1.27 1.27)
				)
			)
		)
		(property "Value" ""
			(at 0 0 270)
			(layer "F.Fab")
			(effects
				(font
					(size 1.27 1.27)
				)
			)
		)
		(duplicate_pad_numbers_are_jumpers no)
		(fp_line
			(start -0.7874 0.4064)
			(end -0.7874 -0.4064)
			(stroke
				(width 0.1524)
				(type default)
			)
			(layer "F.SilkS")
		)
		(fp_line
			(start 0.7874 0.4064)
			(end -0.7874 0.4064)
			(stroke
				(width 0.1524)
				(type default)
			)
			(layer "F.SilkS")
		)
		(fp_line
			(start -0.7874 -0.4064)
			(end 0.7874 -0.4064)
			(stroke
				(width 0.1524)
				(type default)
			)
			(layer "F.SilkS")
		)
		(fp_line
			(start 0.7874 -0.4064)
			(end 0.7874 0.4064)
			(stroke
				(width 0.1524)
				(type default)
			)
			(layer "F.SilkS")
		)
		(fp_line
			(start -0.67945 0.3048)
			(end -0.67945 -0.305054)
			(stroke
				(width 0.1)
				(type default)
			)
			(layer "F.Fab")
		)
		(fp_line
			(start -0.12065 0.3048)
			(end -0.67945 0.3048)
			(stroke
				(width 0.1)
				(type default)
			)
			(layer "F.Fab")
		)
		(fp_line
			(start 0.120396 0.3048)
			(end 0.120396 0.2794)
			(stroke
				(width 0.1)
				(type default)
			)
			(layer "F.Fab")
		)
		(fp_line
			(start 0.67945 0.3048)
			(end 0.120396 0.3048)
			(stroke
				(width 0.1)
				(type default)
			)
			(layer "F.Fab")
		)
		(fp_line
			(start -0.12065 0.2794)
			(end -0.12065 0.3048)
			(stroke
				(width 0.1)
				(type default)
			)
			(layer "F.Fab")
		)
		(fp_line
			(start 0.120396 0.2794)
			(end -0.12065 0.2794)
			(stroke
				(width 0.1)
				(type default)
			)
			(layer "F.Fab")
		)
		(fp_line
			(start -0.12065 -0.2794)
			(end 0.12065 -0.2794)
			(stroke
				(width 0.1)
				(type default)
			)
			(layer "F.Fab")
		)
		(fp_line
			(start 0.12065 -0.2794)
			(end 0.12065 -0.3048)
			(stroke
				(width 0.1)
				(type default)
			)
			(layer "F.Fab")
		)
		(fp_line
			(start 0.12065 -0.3048)
			(end 0.67945 -0.3048)
			(stroke
				(width 0.1)
				(type default)
			)
			(layer "F.Fab")
		)
		(fp_line
			(start 0.67945 -0.3048)
			(end 0.67945 0.3048)
			(stroke
				(width 0.1)
				(type default)
			)
			(layer "F.Fab")
		)
		(fp_line
			(start -0.67945 -0.305054)
			(end -0.12065 -0.305054)
			(stroke
				(width 0.1)
				(type default)
			)
			(layer "F.Fab")
		)
		(fp_line
			(start -0.12065 -0.305054)
			(end -0.12065 -0.2794)
			(stroke
				(width 0.1)
				(type default)
			)
			(layer "F.Fab")
		)
		(pad "1" smd circle
			(at -0.40005 0 270)
			(size 0 0)
			(layers "F.Cu" "F.Mask" "F.Paste")
			(net "PEX3_PCA9555_INT_R_N")
		)
		(pad "2" smd circle
			(at 0.40005 0 270)
			(size 0 0)
			(layers "F.Cu" "F.Mask" "F.Paste")
			(net "P1V8_PEX")
		)
	)
	(footprint ""
		(layer "F.Cu")
		(at 83.034124 -2.998724)
		(property "Reference" "R5813"
			(at 0 0 0)
			(layer "F.SilkS")
			(hide yes)
			(effects
				(font
					(size 1.27 1.27)
				)
			)
		)
		(property "Value" ""
			(at 0 0 0)
			(layer "F.Fab")
			(effects
				(font
					(size 1.27 1.27)
				)
			)
		)
		(duplicate_pad_numbers_are_jumpers no)
		(fp_line
			(start -0.7874 -0.4064)
			(end 0.7874 -0.4064)
			(stroke
				(width 0.1524)
				(type default)
			)
			(layer "F.SilkS")
		)
		(fp_line
			(start -0.7874 0.4064)
			(end -0.7874 -0.4064)
			(stroke
				(width 0.1524)
				(type default)
			)
			(layer "F.SilkS")
		)
		(fp_line
			(start 0.7874 -0.4064)
			(end 0.7874 0.4064)
			(stroke
				(width 0.1524)
				(type default)
			)
			(layer "F.SilkS")
		)
		(fp_line
			(start 0.7874 0.4064)
			(end -0.7874 0.4064)
			(stroke
				(width 0.1524)
				(type default)
			)
			(layer "F.SilkS")
		)
		(fp_line
			(start -0.67945 -0.305054)
			(end -0.12065 -0.305054)
			(stroke
				(width 0.1)
				(type default)
			)
			(layer "F.Fab")
		)
		(fp_line
			(start -0.67945 0.3048)
			(end -0.67945 -0.305054)
			(stroke
				(width 0.1)
				(type default)
			)
			(layer "F.Fab")
		)
		(fp_line
			(start -0.12065 -0.305054)
			(end -0.12065 -0.2794)
			(stroke
				(width 0.1)
				(type default)
			)
			(layer "F.Fab")
		)
		(fp_line
			(start -0.12065 -0.2794)
			(end 0.12065 -0.2794)
			(stroke
				(width 0.1)
				(type default)
			)
			(layer "F.Fab")
		)
		(fp_line
			(start -0.12065 0.2794)
			(end -0.12065 0.3048)
			(stroke
				(width 0.1)
				(type default)
			)
			(layer "F.Fab")
		)
		(fp_line
			(start -0.12065 0.3048)
			(end -0.67945 0.3048)
			(stroke
				(width 0.1)
				(type default)
			)
			(layer "F.Fab")
		)
		(fp_line
			(start 0.120396 0.2794)
			(end -0.12065 0.2794)
			(stroke
				(width 0.1)
				(type default)
			)
			(layer "F.Fab")
		)
		(fp_line
			(start 0.120396 0.3048)
			(end 0.120396 0.2794)
			(stroke
				(width 0.1)
				(type default)
			)
			(layer "F.Fab")
		)
		(fp_line
			(start 0.12065 -0.3048)
			(end 0.67945 -0.3048)
			(stroke
				(width 0.1)
				(type default)
			)
			(layer "F.Fab")
		)
		(fp_line
			(start 0.12065 -0.2794)
			(end 0.12065 -0.3048)
			(stroke
				(width 0.1)
				(type default)
			)
			(layer "F.Fab")
		)
		(fp_line
			(start 0.67945 -0.3048)
			(end 0.67945 0.3048)
			(stroke
				(width 0.1)
				(type default)
			)
			(layer "F.Fab")
		)
		(fp_line
			(start 0.67945 0.3048)
			(end 0.120396 0.3048)
			(stroke
				(width 0.1)
				(type default)
			)
			(layer "F.Fab")
		)
		(pad "1" smd circle
			(at -0.40005 0)
			(size 0 0)
			(layers "F.Cu" "F.Mask" "F.Paste")
			(net "LM75_2_A2")
		)
		(pad "2" smd circle
			(at 0.40005 0)
			(size 0 0)
			(layers "F.Cu" "F.Mask" "F.Paste")
			(net "GND")
		)
	)
	(footprint ""
		(layer "F.Cu")
		(at 324.993 -232.156)
		(property "Reference" "C2841"
			(at 0 0 0)
			(layer "F.SilkS")
			(hide yes)
			(effects
				(font
					(size 1.27 1.27)
				)
			)
		)
		(property "Value" ""
			(at 0 0 0)
			(layer "F.Fab")
			(effects
				(font
					(size 1.27 1.27)
				)
			)
		)
		(duplicate_pad_numbers_are_jumpers no)
		(fp_line
			(start -0.7874 -0.4064)
			(end 0.7874 -0.4064)
			(stroke
				(width 0.1524)
				(type default)
			)
			(layer "F.SilkS")
		)
		(fp_line
			(start -0.7874 0.4064)
			(end -0.7874 -0.4064)
			(stroke
				(width 0.1524)
				(type default)
			)
			(layer "F.SilkS")
		)
		(fp_line
			(start 0.7874 -0.4064)
			(end 0.7874 0.4064)
			(stroke
				(width 0.1524)
				(type default)
			)
			(layer "F.SilkS")
		)
		(fp_line
			(start 0.7874 0.4064)
			(end -0.7874 0.4064)
			(stroke
				(width 0.1524)
				(type default)
			)
			(layer "F.SilkS")
		)
		(fp_line
			(start -0.67945 -0.305054)
			(end -0.12065 -0.305054)
			(stroke
				(width 0.1)
				(type default)
			)
			(layer "F.Fab")
		)
		(fp_line
			(start -0.67945 0.3048)
			(end -0.67945 -0.305054)
			(stroke
				(width 0.1)
				(type default)
			)
			(layer "F.Fab")
		)
		(fp_line
			(start -0.12065 -0.305054)
			(end -0.12065 -0.2794)
			(stroke
				(width 0.1)
				(type default)
			)
			(layer "F.Fab")
		)
		(fp_line
			(start -0.12065 -0.2794)
			(end 0.12065 -0.2794)
			(stroke
				(width 0.1)
				(type default)
			)
			(layer "F.Fab")
		)
		(fp_line
			(start -0.12065 0.2794)
			(end -0.12065 0.3048)
			(stroke
				(width 0.1)
				(type default)
			)
			(layer "F.Fab")
		)
		(fp_line
			(start -0.12065 0.3048)
			(end -0.67945 0.3048)
			(stroke
				(width 0.1)
				(type default)
			)
			(layer "F.Fab")
		)
		(fp_line
			(start 0.120396 0.2794)
			(end -0.12065 0.2794)
			(stroke
				(width 0.1)
				(type default)
			)
			(layer "F.Fab")
		)
		(fp_line
			(start 0.120396 0.3048)
			(end 0.120396 0.2794)
			(stroke
				(width 0.1)
				(type default)
			)
			(layer "F.Fab")
		)
		(fp_line
			(start 0.12065 -0.3048)
			(end 0.67945 -0.3048)
			(stroke
				(width 0.1)
				(type default)
			)
			(layer "F.Fab")
		)
		(fp_line
			(start 0.12065 -0.2794)
			(end 0.12065 -0.3048)
			(stroke
				(width 0.1)
				(type default)
			)
			(layer "F.Fab")
		)
		(fp_line
			(start 0.67945 -0.3048)
			(end 0.67945 0.3048)
			(stroke
				(width 0.1)
				(type default)
			)
			(layer "F.Fab")
		)
		(fp_line
			(start 0.67945 0.3048)
			(end 0.120396 0.3048)
			(stroke
				(width 0.1)
				(type default)
			)
			(layer "F.Fab")
		)
		(pad "1" smd circle
			(at -0.40005 0)
			(size 0 0)
			(layers "F.Cu" "F.Mask" "F.Paste")
			(net "GND")
		)
		(pad "2" smd circle
			(at 0.40005 0)
			(size 0 0)
			(layers "F.Cu" "F.Mask" "F.Paste")
			(net "P3V3_AUX")
		)
	)
	(footprint ""
		(layer "F.Cu")
		(at 377.123706 -306.366418 45)
		(property "Reference" "R1455"
			(at 0 0 45)
			(layer "F.SilkS")
			(hide yes)
			(effects
				(font
					(size 1.27 1.27)
				)
			)
		)
		(property "Value" ""
			(at 0 0 45)
			(layer "F.Fab")
			(effects
				(font
					(size 1.27 1.27)
				)
			)
		)
		(duplicate_pad_numbers_are_jumpers no)
		(fp_line
			(start -0.787389 -0.406267)
			(end 0.787389 -0.406267)
			(stroke
				(width 0.1524)
				(type default)
			)
			(layer "F.SilkS")
		)
		(fp_line
			(start -0.787389 0.406267)
			(end -0.787389 -0.406267)
			(stroke
				(width 0.1524)
				(type default)
			)
			(layer "F.SilkS")
		)
		(fp_line
			(start 0.787389 -0.406267)
			(end 0.787389 0.406267)
			(stroke
				(width 0.1524)
				(type default)
			)
			(layer "F.SilkS")
		)
		(fp_line
			(start 0.787389 0.406267)
			(end -0.787389 0.406267)
			(stroke
				(width 0.1524)
				(type default)
			)
			(layer "F.SilkS")
		)
		(fp_line
			(start -0.679446 -0.305149)
			(end -0.120695 -0.304969)
			(stroke
				(width 0.1)
				(type default)
			)
			(layer "F.Fab")
		)
		(fp_line
			(start -0.120695 -0.304969)
			(end -0.120695 -0.279466)
			(stroke
				(width 0.1)
				(type default)
			)
			(layer "F.Fab")
		)
		(fp_line
			(start -0.120695 -0.279466)
			(end 0.120695 -0.279466)
			(stroke
				(width 0.1)
				(type default)
			)
			(layer "F.Fab")
		)
		(fp_line
			(start -0.679446 0.30479)
			(end -0.679446 -0.305149)
			(stroke
				(width 0.1)
				(type default)
			)
			(layer "F.Fab")
		)
		(fp_line
			(start 0.120515 -0.30479)
			(end 0.679446 -0.30479)
			(stroke
				(width 0.1)
				(type default)
			)
			(layer "F.Fab")
		)
		(fp_line
			(start 0.120695 -0.279466)
			(end 0.120515 -0.30479)
			(stroke
				(width 0.1)
				(type default)
			)
			(layer "F.Fab")
		)
		(fp_line
			(start -0.120695 0.279466)
			(end -0.120515 0.30479)
			(stroke
				(width 0.1)
				(type default)
			)
			(layer "F.Fab")
		)
		(fp_line
			(start -0.120515 0.30479)
			(end -0.679446 0.30479)
			(stroke
				(width 0.1)
				(type default)
			)
			(layer "F.Fab")
		)
		(fp_line
			(start 0.679446 -0.30479)
			(end 0.679446 0.30479)
			(stroke
				(width 0.1)
				(type default)
			)
			(layer "F.Fab")
		)
		(fp_line
			(start 0.120335 0.279466)
			(end -0.120695 0.279466)
			(stroke
				(width 0.1)
				(type default)
			)
			(layer "F.Fab")
		)
		(fp_line
			(start 0.120515 0.30479)
			(end 0.120335 0.279466)
			(stroke
				(width 0.1)
				(type default)
			)
			(layer "F.Fab")
		)
		(fp_line
			(start 0.679446 0.30479)
			(end 0.120515 0.30479)
			(stroke
				(width 0.1)
				(type default)
			)
			(layer "F.Fab")
		)
		(pad "1" smd circle
			(at -0.40005 0 45)
			(size 0 0)
			(layers "F.Cu" "F.Mask" "F.Paste")
			(net "GND")
		)
		(pad "2" smd circle
			(at 0.40005 0 45)
			(size 0 0)
			(layers "F.Cu" "F.Mask" "F.Paste")
			(net "PEX3_DFT_IDDT")
		)
	)
	(footprint ""
		(layer "F.Cu")
		(at 406.166828 -52.543456 180)
		(property "Reference" "PC574"
			(at 0 0 180)
			(layer "F.SilkS")
			(hide yes)
			(effects
				(font
					(size 1.27 1.27)
				)
			)
		)
		(property "Value" ""
			(at 0 0 180)
			(layer "F.Fab")
			(effects
				(font
					(size 1.27 1.27)
				)
			)
		)
		(duplicate_pad_numbers_are_jumpers no)
		(fp_line
			(start 0.7874 0.4064)
			(end -0.7874 0.4064)
			(stroke
				(width 0.1524)
				(type default)
			)
			(layer "F.SilkS")
		)
		(fp_line
			(start 0.7874 -0.4064)
			(end 0.7874 0.4064)
			(stroke
				(width 0.1524)
				(type default)
			)
			(layer "F.SilkS")
		)
		(fp_line
			(start -0.7874 0.4064)
			(end -0.7874 -0.4064)
			(stroke
				(width 0.1524)
				(type default)
			)
			(layer "F.SilkS")
		)
		(fp_line
			(start -0.7874 -0.4064)
			(end 0.7874 -0.4064)
			(stroke
				(width 0.1524)
				(type default)
			)
			(layer "F.SilkS")
		)
		(fp_line
			(start 0.67945 0.3048)
			(end 0.120396 0.3048)
			(stroke
				(width 0.1)
				(type default)
			)
			(layer "F.Fab")
		)
		(fp_line
			(start 0.67945 -0.3048)
			(end 0.67945 0.3048)
			(stroke
				(width 0.1)
				(type default)
			)
			(layer "F.Fab")
		)
		(fp_line
			(start 0.12065 -0.2794)
			(end 0.12065 -0.3048)
			(stroke
				(width 0.1)
				(type default)
			)
			(layer "F.Fab")
		)
		(fp_line
			(start 0.12065 -0.3048)
			(end 0.67945 -0.3048)
			(stroke
				(width 0.1)
				(type default)
			)
			(layer "F.Fab")
		)
		(fp_line
			(start 0.120396 0.3048)
			(end 0.120396 0.2794)
			(stroke
				(width 0.1)
				(type default)
			)
			(layer "F.Fab")
		)
		(fp_line
			(start 0.120396 0.2794)
			(end -0.12065 0.2794)
			(stroke
				(width 0.1)
				(type default)
			)
			(layer "F.Fab")
		)
		(fp_line
			(start -0.12065 0.3048)
			(end -0.67945 0.3048)
			(stroke
				(width 0.1)
				(type default)
			)
			(layer "F.Fab")
		)
		(fp_line
			(start -0.12065 0.2794)
			(end -0.12065 0.3048)
			(stroke
				(width 0.1)
				(type default)
			)
			(layer "F.Fab")
		)
		(fp_line
			(start -0.12065 -0.2794)
			(end 0.12065 -0.2794)
			(stroke
				(width 0.1)
				(type default)
			)
			(layer "F.Fab")
		)
		(fp_line
			(start -0.12065 -0.305054)
			(end -0.12065 -0.2794)
			(stroke
				(width 0.1)
				(type default)
			)
			(layer "F.Fab")
		)
		(fp_line
			(start -0.67945 0.3048)
			(end -0.67945 -0.305054)
			(stroke
				(width 0.1)
				(type default)
			)
			(layer "F.Fab")
		)
		(fp_line
			(start -0.67945 -0.305054)
			(end -0.12065 -0.305054)
			(stroke
				(width 0.1)
				(type default)
			)
			(layer "F.Fab")
		)
		(pad "1" smd circle
			(at -0.40005 0 180)
			(size 0 0)
			(layers "F.Cu" "F.Mask" "F.Paste")
			(net "P3V3_SSD14")
		)
		(pad "2" smd circle
			(at 0.40005 0 180)
			(size 0 0)
			(layers "F.Cu" "F.Mask" "F.Paste")
			(net "GND")
		)
	)
)
